#ISCELL
  mstr_misc dns *
  *
#ISCELL
  pure_quanta quanta_title_block_c *
  *
#ISCELL
  logical_power universal_gnd *
  page303_i1
#CELL
  pure_quanta q_res *
  page303_i10
#ISCELL
  logical_power gnd *
  page303_i11
#CELL
  pure_quanta conn3_210hp1030br1 *
  page303_i12
#ISCELL
  standard offpage *
  page303_i13
#CELL
  pure_quanta q_cap *
  page303_i14
#ISCELL
  standard offpage *
  page303_i15
#CELL
  pure_quanta q_res *
  page303_i17
#ISCELL
  standard offpage *
  page303_i18
#ISCELL
  standard offpage *
  page303_i19
#ISCELL
  standard offpage *
  page303_i2
#ISCELL
  standard offpage *
  page303_i21
#ISCELL
  logical_power universal_gnd *
  page303_i22
#CELL
  pure_quanta q_cap *
  page303_i23
#CELL
  pure_quanta q_res *
  page303_i24
#CELL
  pure_quanta q_res *
  page303_i26
#ISCELL
  standard offpage *
  page303_i27
#ISCELL
  logical_power universal_gnd *
  page303_i28
#CELL
  pure_quanta q_cap *
  page303_i29
#CELL
  pure_quanta q_cap *
  page303_i3
#ISCELL
  standard offpage *
  page303_i30
#ISCELL
  logical_power universal_gnd *
  page303_i31
#CELL
  pure_quanta q_res *
  page303_i32
#CELL
  pure_quanta q_res *
  page303_i33
#ISCELL
  logical_power universal_power *
  page303_i34
#CELL
  pure_quanta q_cap *
  page303_i35
#ISCELL
  logical_power universal_power *
  page303_i36
#CELL
  pure_quanta q_res *
  page303_i37
#CELL
  pure_quanta q_res *
  page303_i38
#ISCELL
  logical_power universal_gnd *
  page303_i39
#CELL
  pure_quanta q_res *
  page303_i4
#CELL
  pure_quanta q_res *
  page303_i40
#CELL
  pure_quanta q_res *
  page303_i41
#CELL
  pure_quanta q_res *
  page303_i42
#CELL
  pure_quanta q_res *
  page303_i43
#CELL
  pure_quanta q_res *
  page303_i44
#CELL
  pure_quanta q_cap *
  page303_i45
#ISCELL
  logical_power universal_power *
  page303_i47
#CELL
  pure_quanta mosfet_nch_gds_esd_protected *
  page303_i5
#ISCELL
  logical_power universal_power *
  page303_i50
#CELL
  pure_quanta q_cap *
  page303_i51
#CELL
  pure_quanta q_res *
  page303_i52
#ISCELL
  logical_power gnd *
  page303_i53
#CELL
  pure_quanta q_res *
  page303_i54
#ISCELL
  logical_power universal_gnd *
  page303_i55
#CELL
  pure_quanta mp5990gma1111z *
  page303_i56
#ISCELL
  logical_power universal_gnd *
  page303_i57
#CELL
  pure_quanta q_res *
  page303_i58
#CELL
  pure_quanta q_res *
  page303_i59
#ISCELL
  logical_power gnd *
  page303_i6
#ISCELL
  logical_power universal_gnd *
  page303_i60
#CELL
  pure_quanta q_res *
  page303_i61
#CELL
  pure_quanta q_res *
  page303_i62
#ISCELL
  standard offpage *
  page303_i63
#ISCELL
  logical_power universal_gnd *
  page303_i64
#ISCELL
  standard offpage *
  page303_i65
#ISCELL
  standard offpage *
  page303_i66
#ISCELL
  standard offpage *
  page303_i67
#ISCELL
  logical_power universal_power *
  page303_i68
#CELL
  pure_quanta q_cap *
  page303_i69
#CELL
  pure_quanta q_res *
  page303_i7
#ISCELL
  standard offpage *
  page303_i70
#ISCELL
  logical_power universal_gnd *
  page303_i71
#ISCELL
  standard offpage *
  page303_i72
#ISCELL
  standard offpage *
  page303_i73
#ISCELL
  logical_power universal_gnd *
  page303_i74
#CELL
  pure_quanta q_cap *
  page303_i75
#CELL
  pure_quanta q_cap *
  page303_i77
#ISCELL
  logical_power universal_gnd *
  page303_i78
#CELL
  pure_quanta q_res *
  page303_i79
#ISCELL
  logical_power gnd *
  page303_i8
#ISCELL
  standard offpage *
  page303_i80
#CELL
  pure_quanta q_res *
  page303_i81
#CELL
  pure_quanta q_res *
  page303_i82
#CELL
  pure_quanta q_res *
  page303_i84
#CELL
  pure_quanta q_res *
  page303_i85
#CELL
  pure_quanta q_res *
  page303_i86
#ISCELL
  logical_power universal_power *
  page303_i87
#ISCELL
  logical_power universal_power *
  page303_i88
#CELL
  pure_quanta q_cap *
  page303_i89
#ISCELL
  logical_power universal_gnd *
  page303_i9
#ISCELL
  logical_power universal_gnd *
  page303_i90
#CELL
  pure_quanta q_res *
  page303_i91
#ISCELL
  standard offpage *
  page303_i92
#CELL
  pure_quanta q_res *
  page303_i93
#ISCELL
  logical_power universal_gnd *
  page303_i94
#ISCELL
  standard offpage *
  page303_i95
#ISCELL
  standard offpage *
  page303_i96
#ISCELL
  logical_power gnd *
  page303_i97
